# T6G (Grand Teton) — schematic netlist excerpt (pin names and nets, part order shuffled) for the footprints in the layout excerpt that follows; sources: Cadence DE-HDL packaged netlist, KiCad conversion of 04192023_DAF0TMB3IC0_F0TG_MB_C_brd_V02_OCP.brd

C6019  Q_CAP_DIFFBUS  DIFF BUS_0.33UF 6.3V 10% X6S  pkg C0402  page 180 : \1\ = USB3_CPU0_BMC_RX_DP ; \2\ = USB3_CPU0_BMC_RX_C1_DP
D6000  Q_LED  IC  pkg SMLF  page 254 : A = LED_PWRGD_P1V2_AUX ; C = LED_PWRGD_P1V2_AUX_D

(kicad_pcb
	(version 20260206)
	(generator "pcbnew")
	(generator_version "10.0")
	(general
		(thickness 1.6)
		(legacy_teardrops no)
	)
	(paper "A4")
	(title_block
		(title "04192023_DAF0TMB3IC0_F0TG_MB_C_brd_V02_OCP.brd")
		(comment 1 "Grand Teton / footprints 403-404 of 8354")
	)
	(layers
		(0 "F.Cu" signal "TOP")
		(4 "In1.Cu" signal "GND")
		(6 "In2.Cu" signal "IN1")
		(8 "In3.Cu" signal "GND1")
		(10 "In4.Cu" signal "IN2")
		(12 "In5.Cu" signal "GND2")
		(14 "In6.Cu" signal "IN3")
		(16 "In7.Cu" signal "GND3")
		(18 "In8.Cu" signal "VCC")
		(20 "In9.Cu" signal "VCC1")
		(22 "In10.Cu" signal "GND4")
		(24 "In11.Cu" signal "IN4")
		(26 "In12.Cu" signal "GND5")
		(28 "In13.Cu" signal "IN5")
		(30 "In14.Cu" signal "GND6")
		(32 "In15.Cu" signal "IN6")
		(34 "In16.Cu" signal "GND7")
		(2 "B.Cu" signal "BOTTOM")
		(9 "F.Adhes" user "F.Adhesive")
		(11 "B.Adhes" user "B.Adhesive")
		(13 "F.Paste" user "Package Geometry/Pastemask Top")
		(15 "B.Paste" user "Package Geometry/Pastemask Bottom")
		(5 "F.SilkS" user "Ref Des/Silkscreen Top")
		(7 "B.SilkS" user "Ref Des/Silkscreen Bottom")
		(1 "F.Mask" user "Board Geometry/Soldermask Top")
		(3 "B.Mask" user "Board Geometry/Soldermask Bottom")
		(17 "Dwgs.User" user "User.Drawings")
		(19 "Cmts.User" user "User.Comments")
		(21 "Eco1.User" user "User.Eco1")
		(23 "Eco2.User" user "User.Eco2")
		(25 "Edge.Cuts" user "Board Geometry/Outline")
		(27 "Margin" user)
		(31 "F.CrtYd" user "Package Geometry/Place Bound Top")
		(29 "B.CrtYd" user "Package Geometry/Place Bound Bottom")
		(35 "F.Fab" user "Ref Des/Assembly Top")
		(33 "B.Fab" user "Ref Des/Assembly Bottom")
	)
	(footprint ""
		(layer "F.Cu")
		(at 125.38837 -32.751268)
		(property "Reference" "C6019"
			(at 0 0 0)
			(layer "F.SilkS")
			(hide yes)
			(effects
				(font
					(size 1.27 1.27)
				)
			)
		)
		(property "Value" ""
			(at 0 0 0)
			(layer "F.Fab")
			(effects
				(font
					(size 1.27 1.27)
				)
			)
		)
		(duplicate_pad_numbers_are_jumpers no)
		(fp_line
			(start -0.40005 -0.4064)
			(end 0.40005 -0.4064)
			(stroke
				(width 0.1524)
				(type default)
			)
			(layer "F.SilkS")
		)
		(fp_line
			(start 0.40005 0.4064)
			(end -0.40005 0.4064)
			(stroke
				(width 0.1524)
				(type default)
			)
			(layer "F.SilkS")
		)
		(fp_line
			(start -0.6858 -0.3048)
			(end -0.1016 -0.3048)
			(stroke
				(width 0.1)
				(type default)
			)
			(layer "F.Fab")
		)
		(fp_line
			(start -0.6858 0.3048)
			(end -0.6858 -0.3048)
			(stroke
				(width 0.1)
				(type default)
			)
			(layer "F.Fab")
		)
		(fp_line
			(start -0.1016 -0.3048)
			(end -0.1016 -0.2794)
			(stroke
				(width 0.1)
				(type default)
			)
			(layer "F.Fab")
		)
		(fp_line
			(start -0.1016 -0.2794)
			(end 0.1016 -0.2794)
			(stroke
				(width 0.1)
				(type default)
			)
			(layer "F.Fab")
		)
		(fp_line
			(start -0.1016 0.2794)
			(end -0.1016 0.3048)
			(stroke
				(width 0.1)
				(type default)
			)
			(layer "F.Fab")
		)
		(fp_line
			(start -0.1016 0.3048)
			(end -0.6858 0.3048)
			(stroke
				(width 0.1)
				(type default)
			)
			(layer "F.Fab")
		)
		(fp_line
			(start 0.1016 -0.3048)
			(end 0.6858 -0.3048)
			(stroke
				(width 0.1)
				(type default)
			)
			(layer "F.Fab")
		)
		(fp_line
			(start 0.1016 -0.2794)
			(end 0.1016 -0.3048)
			(stroke
				(width 0.1)
				(type default)
			)
			(layer "F.Fab")
		)
		(fp_line
			(start 0.1016 0.2794)
			(end -0.1016 0.2794)
			(stroke
				(width 0.1)
				(type default)
			)
			(layer "F.Fab")
		)
		(fp_line
			(start 0.1016 0.3048)
			(end 0.1016 0.2794)
			(stroke
				(width 0.1)
				(type default)
			)
			(layer "F.Fab")
		)
		(fp_line
			(start 0.6858 -0.3048)
			(end 0.6858 0.3048)
			(stroke
				(width 0.1)
				(type default)
			)
			(layer "F.Fab")
		)
		(fp_line
			(start 0.6858 0.3048)
			(end 0.1016 0.3048)
			(stroke
				(width 0.1)
				(type default)
			)
			(layer "F.Fab")
		)
		(pad "1" smd rect
			(at -0.40005 0 180)
			(size 0.4572 0.508)
			(layers "F.Cu" "F.Mask" "F.Paste")
			(net "USB3_CPU0_BMC_RX_DP")
		)
		(pad "2" smd rect
			(at 0.40005 0 180)
			(size 0.4572 0.508)
			(layers "F.Cu" "F.Mask" "F.Paste")
			(net "USB3_CPU0_BMC_RX_C1_DP")
		)
	)
	(footprint ""
		(layer "F.Cu")
		(at 308.379876 -70.098412 90)
		(property "Reference" "D6000"
			(at -3.75158 -1.438148 90)
			(unlocked yes)
			(layer "F.SilkS")
			(effects
				(font
					(size 0.7874 0.5842)
					(thickness 0.1524)
				)
				(justify left)
			)
		)
		(property "Value" ""
			(at 0 0 90)
			(layer "F.Fab")
			(effects
				(font
					(size 1.27 1.27)
				)
			)
		)
		(duplicate_pad_numbers_are_jumpers no)
		(fp_line
			(start 1.16078 -0.4826)
			(end 1.16078 0.4826)
			(stroke
				(width 0.1524)
				(type default)
			)
			(layer "F.SilkS")
		)
		(fp_line
			(start 1.03378 -0.4826)
			(end 1.03378 0.4826)
			(stroke
				(width 0.1524)
				(type default)
			)
			(layer "F.SilkS")
		)
		(fp_line
			(start 0.90678 -0.4826)
			(end 0.90678 0.4826)
			(stroke
				(width 0.1524)
				(type default)
			)
			(layer "F.SilkS")
		)
		(fp_line
			(start -0.64008 -0.4826)
			(end 1.16078 -0.4826)
			(stroke
				(width 0.1524)
				(type default)
			)
			(layer "F.SilkS")
		)
		(fp_line
			(start -0.79248 -0.4826)
			(end 1.03378 -0.4826)
			(stroke
				(width 0.1524)
				(type default)
			)
			(layer "F.SilkS")
		)
		(fp_line
			(start -0.89408 -0.4826)
			(end 0.90678 -0.4826)
			(stroke
				(width 0.1524)
				(type default)
			)
			(layer "F.SilkS")
		)
		(fp_line
			(start 1.16078 0.4826)
			(end -0.64008 0.4826)
			(stroke
				(width 0.1524)
				(type default)
			)
			(layer "F.SilkS")
		)
		(fp_line
			(start 1.03378 0.4826)
			(end -0.79248 0.4826)
			(stroke
				(width 0.1524)
				(type default)
			)
			(layer "F.SilkS")
		)
		(fp_line
			(start 0.90678 0.4826)
			(end -0.90678 0.4826)
			(stroke
				(width 0.1524)
				(type default)
			)
			(layer "F.SilkS")
		)
		(fp_line
			(start -0.90678 0.4826)
			(end -0.90678 -0.4699)
			(stroke
				(width 0.1524)
				(type default)
			)
			(layer "F.SilkS")
		)
		(fp_line
			(start 0.499872 -0.249936)
			(end 0.499872 0.249936)
			(stroke
				(width 0.1)
				(type default)
			)
			(layer "F.Fab")
		)
		(fp_line
			(start -0.499872 -0.249936)
			(end 0.499872 -0.249936)
			(stroke
				(width 0.1)
				(type default)
			)
			(layer "F.Fab")
		)
		(fp_line
			(start 0.499872 0.249936)
			(end -0.499872 0.249936)
			(stroke
				(width 0.1)
				(type default)
			)
			(layer "F.Fab")
		)
		(fp_line
			(start -0.499872 0.249936)
			(end -0.499872 -0.249936)
			(stroke
				(width 0.1)
				(type default)
			)
			(layer "F.Fab")
		)
		(pad "A" smd rect
			(at -0.47498 0 90)
			(size 0.6096 0.7112)
			(layers "F.Cu" "F.Mask" "F.Paste")
			(net "LED_PWRGD_P1V2_AUX")
		)
		(pad "C" smd rect
			(at 0.47498 0 90)
			(size 0.6096 0.7112)
			(layers "F.Cu" "F.Mask" "F.Paste")
			(net "LED_PWRGD_P1V2_AUX_D")
		)
	)
)
